# OAM_Pin list_Rev1.0.xlsx — Rev History (pin-map)
| Rev | Date | Changes |
| 0.1-0.8 |  | Internal release |
| 0.81 | 43412 | *Changed first column as OCP signal name and change all signals to generic pin names (remove any Mad/Intel specific).  *Added Serial port pins and 5 additional TEST pins |
| 0.82 | 43413 | Change SerDes OCP signal names back to 1 through 7 |
| 0.83 | 43413 | Updated the "LINK_CONFIG[0:3] to LINK_CONFIG[0:4]"   as we actually have 5 topology ID bits. |
| 0.84 | 43424 | *Updated OCP Generic pin names *Added Reserve link bifurcation pins *Added PCIe Link Module capability signal *Added Serial port pins *Added Intel "Test" pins. Need to agreed in test/debug access solution from Module to Motherboard |
| 0.85 | 43433 | *Updated description of PLINK_CAP pins *Added I/O Direction and OCP Pin description columns *Reordered Misc signals across connector 0 and 1 *Re-named P12V and P12V_M pins to P12V1 and P12V2 *Renamed Vref to PLVIO *Added TEST7, TEST8, TEST9 for Intel test pins *Added RSVD2, RSVD3, RSVD4  *Added On Board Manager Controller status LEDs: Green, Blue, Red *Added QSFP-DD cable management side band signals |
| 0.86 | 43448 | *Added Test 12, TEST13 and TEST14 *Change TEST 10 to 14 from Connector 0 to Connector 1 |
| 0.87 | 2/05/20019 | *Changed QSFP Signals to be LV I/O *Changed QSFP side band signals pins negative logic indication from _N to # *Updated 12V and 48V pin count *Updated SerDes 3 to x16 instead of x20 *Added THERMTRIP#  *Removed RLINK_CAP[1:0] *Removed STATUS_LED_GREEN, STATUS_LED_RED, STATUS_LED_BLUE *Added SCALE_DEBUG_EN# *Added DEBUG_PORT_PRSNT# *Renamed RSVD Diff pairs to MNGT_LINKxTp/n *Renamed RSVD2 to MANF_MODE# *Renamed RSVD3 to FW_RECOVERY# *Renamed RSVD4 to TEST_MODE# *Changed Signal direction on SERDES_Rxx and PExx following Mezz Module POV convention *Added column to indicate whether or not each signal is required for the "common accelerator motherboard solution"  *Changed PLINK_CAP from Output to Input *Changed PLVIO to PVREF |
| 0.88 | 43532 | *Added AUX_156M_REFCLKp/n for 156.25MHz auxiliary reference clock in connector 1 *Changed AUX_REFCLKp/n to AUX_100M_REFCLKp/n signal name *Changed SCALE_DEBUG_EN_N to SCALE_DEBUG_EN, changed from logic low to  logic high |
| 1 | 43671 | *Changed SerDes R from 20 bits to 16-bits *Update Vref range to 1.5V to 3.3V *Added PWRRDT#0 and PWRRDT#1 for Intel OAM power reduction *Renamed SerDes R to SerDes 7 *Renamed SerDes 6 to SerDes 4 *Renamed SerDes 4 to SerDes 6 *add "OAM Baseboard implemention Recommendation" on column F.  *update Molex conn PN and info |
